(kicad_pcb
	(version 20260206)
	(generator "pcbnew")
	(generator_version "10.0")
	(general
		(thickness 1.6)
		(legacy_teardrops no)
	)
	(paper "A4")
	(title_block
		(title "Bryce Canyon_F.DPB_16315-1-OCP.brd")
		(comment 1 "Bryce Canyon / footprints 1681-1683 of 2223")
	)
	(layers
		(0 "F.Cu" signal "TOP")
		(4 "In1.Cu" signal "L2GND")
		(6 "In2.Cu" signal "L3")
		(8 "In3.Cu" signal "L4GND")
		(10 "In4.Cu" signal "L5")
		(12 "In5.Cu" signal "L6VCC")
		(14 "In6.Cu" signal "L7VCC")
		(16 "In7.Cu" signal "L8")
		(18 "In8.Cu" signal "L9GND")
		(20 "In9.Cu" signal "L10")
		(22 "In10.Cu" signal "L11GND")
		(2 "B.Cu" signal "BOTTOM")
		(9 "F.Adhes" user "F.Adhesive")
		(11 "B.Adhes" user "B.Adhesive")
		(13 "F.Paste" user "Package Geometry/Pastemask Top")
		(15 "B.Paste" user "Package Geometry/Pastemask Bottom")
		(5 "F.SilkS" user "Ref Des/Silkscreen Top")
		(7 "B.SilkS" user "Ref Des/Silkscreen Bottom")
		(1 "F.Mask" user "Board Geometry/Soldermask Top")
		(3 "B.Mask" user "Board Geometry/Soldermask Bottom")
		(17 "Dwgs.User" user "User.Drawings")
		(19 "Cmts.User" user "User.Comments")
		(21 "Eco1.User" user "User.Eco1")
		(23 "Eco2.User" user "User.Eco2")
		(25 "Edge.Cuts" user "Board Geometry/Outline")
		(27 "Margin" user)
		(31 "F.CrtYd" user "Package Geometry/Place Bound Top")
		(29 "B.CrtYd" user "Package Geometry/Place Bound Bottom")
		(35 "F.Fab" user "Ref Des/Assembly Top")
		(33 "B.Fab" user "Ref Des/Assembly Bottom")
	)
	(footprint ""
		(layer "F.Cu")
		(at 132.718302 -303.893728)
		(property "Reference" "Q255"
			(at 0 0 0)
			(layer "F.SilkS")
			(hide yes)
			(effects
				(font
					(size 1.27 1.27)
				)
			)
		)
		(property "Value" "2N7002K-2-GP"
			(at 0.127 -8.9662 0)
			(unlocked yes)
			(layer "F.Fab")
			(hide yes)
			(effects
				(font
					(size 1.016 1.016)
					(thickness 0.1524)
				)
			)
		)
		(property "Device Type" "SOT23DGS2D4H44"
			(at 0.127 -10.4902 0)
			(unlocked yes)
			(layer "F.Fab")
			(hide yes)
			(effects
				(font
					(size 1.016 1.016)
					(thickness 0.1524)
				)
			)
		)
		(duplicate_pad_numbers_are_jumpers no)
		(fp_line
			(start -1.651 -1.778)
			(end -1.651 1.778)
			(stroke
				(width 0.1524)
				(type default)
			)
			(layer "F.SilkS")
		)
		(fp_line
			(start -1.651 1.778)
			(end 1.651 1.778)
			(stroke
				(width 0.1524)
				(type default)
			)
			(layer "F.SilkS")
		)
		(fp_line
			(start 1.651 -1.778)
			(end -1.651 -1.778)
			(stroke
				(width 0.1524)
				(type default)
			)
			(layer "F.SilkS")
		)
		(fp_line
			(start 1.651 1.778)
			(end 1.651 -1.778)
			(stroke
				(width 0.1524)
				(type default)
			)
			(layer "F.SilkS")
		)
		(fp_poly
			(pts
				(xy -1.778 1.8796) (xy -1.778 -1.8796) (xy 1.778 -1.8796) (xy 1.778 1.8796)
			)
			(stroke
				(width 0)
				(type default)
			)
			(fill no)
			(layer "F.CrtYd")
		)
		(fp_poly
			(pts
				(xy -1.778 1.8796) (xy -1.778 -1.8796) (xy 1.778 -1.8796) (xy 1.778 1.8796)
			)
			(stroke
				(width 0)
				(type default)
			)
			(fill no)
			(layer "F.Fab")
		)
		(pad "D" smd custom
			(at 0 -0.9525)
			(size 0.1905 0.1905)
			(layers "F.Cu" "F.Mask" "F.Paste")
			(net "FLT_HDD28_N")
			(options
				(clearance outline)
				(anchor circle)
			)
			(primitives
				(gr_poly
					(pts
						(arc
							(start -0.1778 0.5715)
							(mid -0.321484 0.511984)
							(end -0.381 0.3683)
						)
						(arc
							(start -0.381 -0.3683)
							(mid -0.321484 -0.511984)
							(end -0.1778 -0.5715)
						)
						(arc
							(start 0.1778 -0.5715)
							(mid 0.321484 -0.511984)
							(end 0.381 -0.3683)
						)
						(arc
							(start 0.381 0.3683)
							(mid 0.321484 0.511984)
							(end 0.1778 0.5715)
						)
					)
					(width 0)
					(fill yes)
				)
			)
		)
		(pad "G" smd custom
			(at -0.98425 0.9525)
			(size 0.1905 0.1905)
			(layers "F.Cu" "F.Mask" "F.Paste")
			(net "DRIVE_B_28_FLT_LED")
			(options
				(clearance outline)
				(anchor circle)
			)
			(primitives
				(gr_poly
					(pts
						(arc
							(start -0.1778 0.5715)
							(mid -0.321484 0.511984)
							(end -0.381 0.3683)
						)
						(arc
							(start -0.381 -0.3683)
							(mid -0.321484 -0.511984)
							(end -0.1778 -0.5715)
						)
						(arc
							(start 0.1778 -0.5715)
							(mid 0.321484 -0.511984)
							(end 0.381 -0.3683)
						)
						(arc
							(start 0.381 0.3683)
							(mid 0.321484 0.511984)
							(end 0.1778 0.5715)
						)
					)
					(width 0)
					(fill yes)
				)
			)
		)
		(pad "S" smd custom
			(at 0.98425 0.9525)
			(size 0.1905 0.1905)
			(layers "F.Cu" "F.Mask" "F.Paste")
			(net "GND")
			(options
				(clearance outline)
				(anchor circle)
			)
			(primitives
				(gr_poly
					(pts
						(arc
							(start -0.1778 0.5715)
							(mid -0.321484 0.511984)
							(end -0.381 0.3683)
						)
						(arc
							(start -0.381 -0.3683)
							(mid -0.321484 -0.511984)
							(end -0.1778 -0.5715)
						)
						(arc
							(start 0.1778 -0.5715)
							(mid 0.321484 -0.511984)
							(end 0.381 -0.3683)
						)
						(arc
							(start 0.381 0.3683)
							(mid 0.321484 0.511984)
							(end 0.1778 0.5715)
						)
					)
					(width 0)
					(fill yes)
				)
			)
		)
	)
	(footprint ""
		(layer "F.Cu")
		(at 276.098 -272.288 180)
		(property "Reference" "R112"
			(at 0 0 180)
			(layer "F.SilkS")
			(hide yes)
			(effects
				(font
					(size 1.27 1.27)
				)
			)
		)
		(property "Value" "4K7R2F-GP"
			(at 0.064008 -3.993896 180)
			(unlocked yes)
			(layer "F.Fab")
			(hide yes)
			(effects
				(font
					(size 1.016 1.016)
					(thickness 0.1524)
				)
			)
		)
		(property "Device Type" "R402H16"
			(at 0.064008 -5.517896 180)
			(unlocked yes)
			(layer "F.Fab")
			(hide yes)
			(effects
				(font
					(size 1.016 1.016)
					(thickness 0.1524)
				)
			)
		)
		(duplicate_pad_numbers_are_jumpers no)
		(fp_line
			(start 0.508 -0.9398)
			(end -0.508 -0.9398)
			(stroke
				(width 0.1524)
				(type default)
			)
			(layer "F.SilkS")
		)
		(fp_line
			(start -0.508 -0.9398)
			(end -0.508 0.9398)
			(stroke
				(width 0.1524)
				(type default)
			)
			(layer "F.SilkS")
		)
		(fp_rect
			(start -0.508 0.9398)
			(end 0.508 -0.9398)
			(stroke
				(width 0)
				(type default)
			)
			(fill no)
			(layer "F.CrtYd")
		)
		(fp_rect
			(start -0.508 0.9398)
			(end 0.508 -0.9398)
			(stroke
				(width 0)
				(type default)
			)
			(fill no)
			(layer "F.Fab")
		)
		(pad "1" smd custom
			(at 0 -0.4445 180)
			(size 0.1397 0.1397)
			(layers "F.Cu" "F.Mask" "F.Paste")
			(net "P3V3_STBY_A")
			(options
				(clearance outline)
				(anchor circle)
			)
			(primitives
				(gr_poly
					(pts
						(arc
							(start -0.1778 -0.2794)
							(mid -0.249642 -0.249642)
							(end -0.2794 -0.1778)
						)
						(arc
							(start -0.2794 0.1778)
							(mid -0.249642 0.249642)
							(end -0.1778 0.2794)
						)
						(arc
							(start 0.1778 0.2794)
							(mid 0.249642 0.249642)
							(end 0.2794 0.1778)
						)
						(arc
							(start 0.2794 -0.1778)
							(mid 0.249642 -0.249642)
							(end 0.1778 -0.2794)
						)
					)
					(width 0)
					(fill yes)
				)
			)
		)
		(pad "2" smd custom
			(at 0 0.4445 180)
			(size 0.1397 0.1397)
			(layers "F.Cu" "F.Mask" "F.Paste")
			(net "IO_EXP1_HDD_FAULT_A2")
			(options
				(clearance outline)
				(anchor circle)
			)
			(primitives
				(gr_poly
					(pts
						(arc
							(start -0.1778 -0.2794)
							(mid -0.249642 -0.249642)
							(end -0.2794 -0.1778)
						)
						(arc
							(start -0.2794 0.1778)
							(mid -0.249642 0.249642)
							(end -0.1778 0.2794)
						)
						(arc
							(start 0.1778 0.2794)
							(mid 0.249642 0.249642)
							(end 0.2794 0.1778)
						)
						(arc
							(start 0.2794 -0.1778)
							(mid 0.249642 -0.249642)
							(end 0.1778 -0.2794)
						)
					)
					(width 0)
					(fill yes)
				)
			)
		)
	)
	(footprint ""
		(layer "F.Cu")
		(at 260.150102 29.249878 180)
		(property "Reference" "IO3"
			(at 0 0 180)
			(layer "F.SilkS")
			(hide yes)
			(effects
				(font
					(size 1.27 1.27)
				)
			)
		)
		(property "Value" "SKT-SAS15P-14P-45-GP"
			(at -20.7645 -8.9789 180)
			(unlocked yes)
			(layer "F.Fab")
			(hide yes)
			(effects
				(font
					(size 1.016 1.016)
					(thickness 0.1524)
				)
			)
		)
		(property "Device Type" "10120818-001C-TRLF"
			(at -20.7645 -10.5029 180)
			(unlocked yes)
			(layer "F.Fab")
			(hide yes)
			(effects
				(font
					(size 1.016 1.016)
					(thickness 0.1524)
				)
			)
		)
		(duplicate_pad_numbers_are_jumpers no)
		(fp_line
			(start 23.4188 3.0099)
			(end 8.509 3.0099)
			(stroke
				(width 0.1524)
				(type default)
			)
			(layer "F.SilkS")
		)
		(fp_line
			(start 23.4188 -3.2512)
			(end 23.4188 3.0099)
			(stroke
				(width 0.1524)
				(type default)
			)
			(layer "F.SilkS")
		)
		(fp_line
			(start 15.5067 -3.3401)
			(end 16.2687 -3.3401)
			(stroke
				(width 0.3302)
				(type default)
			)
			(layer "F.SilkS")
		)
		(fp_line
			(start 8.509 4.2926)
			(end 1.651 4.2926)
			(stroke
				(width 0.1524)
				(type default)
			)
			(layer "F.SilkS")
		)
		(fp_line
			(start 8.509 3.0099)
			(end 8.509 4.2926)
			(stroke
				(width 0.1524)
				(type default)
			)
			(layer "F.SilkS")
		)
		(fp_line
			(start 1.651 4.2926)
			(end 1.651 3.0099)
			(stroke
				(width 0.1524)
				(type default)
			)
			(layer "F.SilkS")
		)
		(fp_line
			(start 1.651 3.0099)
			(end -23.4188 3.0099)
			(stroke
				(width 0.1524)
				(type default)
			)
			(layer "F.SilkS")
		)
		(fp_line
			(start -23.4188 3.0099)
			(end -23.4188 -3.2512)
			(stroke
				(width 0.1524)
				(type default)
			)
			(layer "F.SilkS")
		)
		(fp_line
			(start -23.4188 -3.2512)
			(end 23.4188 -3.2512)
			(stroke
				(width 0.1524)
				(type default)
			)
			(layer "F.SilkS")
		)
		(fp_poly
			(pts
				(xy 15.868904 -3.230372) (xy 16.503904 -3.865372) (xy 15.233904 -3.865372)
			)
			(stroke
				(width 0)
				(type default)
			)
			(fill yes)
			(layer "F.SilkS")
		)
		(fp_poly
			(pts
				(xy -22.8727 -2.7559) (xy 22.8727 -2.7559) (xy 22.8727 2.7559) (xy 8.255 2.7559) (xy 8.255 3.5179)
				(xy 1.905 3.5179) (xy 1.905 2.7559) (xy -22.8727 2.7559)
			)
			(stroke
				(width 0)
				(type default)
			)
			(fill no)
			(layer "F.CrtYd")
		)
		(fp_poly
			(pts
				(xy 1.397 4.5466) (xy 1.397 3.2639) (xy -23.6728 3.2639) (xy -23.6728 -3.5052) (xy 23.6728 -3.5052)
				(xy 23.6728 -0.00635) (xy 22.8727 -0.00635) (xy 22.8727 -2.7559) (xy -22.8727 -2.7559) (xy -22.8727 2.7559)
				(xy 1.905 2.7559) (xy 1.905 3.5179) (xy 8.255 3.5179) (xy 8.255 2.7559) (xy 22.8727 2.7559) (xy 22.8727 0.00635)
				(xy 23.6728 0.00635) (xy 23.6728 3.2639) (xy 8.763 3.2639) (xy 8.763 4.5466)
			)
			(stroke
				(width 0)
				(type default)
			)
			(fill no)
			(layer "F.CrtYd")
		)
		(fp_poly
			(pts
				(xy 1.397 4.5466) (xy 1.397 3.2639) (xy -23.6728 3.2639) (xy -23.6728 -3.5052) (xy 23.6728 -3.5052)
				(xy 23.6728 3.2639) (xy 8.763 3.2639) (xy 8.763 4.5466)
			)
			(stroke
				(width 0)
				(type default)
			)
			(fill no)
			(layer "F.Fab")
		)
		(pad "" np_thru_hole circle
			(at -18.874994 0 180)
			(size 0.254 0.254)
			(drill 1.3462)
			(layers "*.Cu" "*.Mask")
			(clearance 0.9017)
			(thermal_gap 0.9017)
		)
		(pad "" np_thru_hole circle
			(at 18.874994 0 180)
			(size 0.254 0.254)
			(drill 0.9398)
			(layers "*.Cu" "*.Mask")
			(clearance 0.6985)
			(thermal_gap 0.6985)
		)
		(pad "G1" smd rect
			(at 21.874988 0 180)
			(size 2.5908 2.5908)
			(layers "F.Cu" "F.Mask" "F.Paste")
			(net "GND")
		)
		(pad "G2" smd rect
			(at -21.874988 0 180)
			(size 2.5908 2.5908)
			(layers "F.Cu" "F.Mask" "F.Paste")
			(net "GND")
		)
		(pad "P1" smd rect
			(at 1.905 -1.82499 180)
			(size 0.6096 2.3622)
			(layers "F.Cu" "F.Mask" "F.Paste")
			(net "P5V_USB_A")
		)
		(pad "P2" smd rect
			(at 0.635 -1.82499 180)
			(size 0.6096 2.3622)
			(layers "F.Cu" "F.Mask" "F.Paste")
			(net "P5V_USB_B")
		)
		(pad "P3" smd rect
			(at -0.635 -1.82499 180)
			(size 0.6096 2.3622)
			(layers "F.Cu" "F.Mask" "F.Paste")
			(net "ENCL_FAULT_LED_B")
		)
		(pad "P4" smd rect
			(at -1.905 -1.82499 180)
			(size 0.6096 2.3622)
			(layers "F.Cu" "F.Mask" "F.Paste")
			(net "SYS_PWR_LED_B")
		)
		(pad "P5" smd rect
			(at -3.175 -1.82499 180)
			(size 0.6096 2.3622)
			(layers "F.Cu" "F.Mask" "F.Paste")
			(net "P3V3_STBY_B")
		)
		(pad "P6" smd rect
			(at -4.445 -1.82499 180)
			(size 0.6096 2.3622)
			(layers "F.Cu" "F.Mask" "F.Paste")
			(net "RST_BTN_B_N")
		)
		(pad "P7" smd rect
			(at -5.715 -1.82499 180)
			(size 0.6096 2.3622)
			(layers "F.Cu" "F.Mask" "F.Paste")
			(net "GND")
		)
		(pad "P8" smd rect
			(at -6.985 -1.82499 180)
			(size 0.6096 2.3622)
			(layers "F.Cu" "F.Mask" "F.Paste")
			(net "I2C_DPB_B_SCL")
		)
		(pad "P9" smd rect
			(at -8.255 -1.82499 180)
			(size 0.6096 2.3622)
			(layers "F.Cu" "F.Mask" "F.Paste")
			(net "I2C_DPB_B_SDA")
		)
		(pad "P10" smd rect
			(at -9.525 -1.82499 180)
			(size 0.6096 2.3622)
			(layers "F.Cu" "F.Mask" "F.Paste")
			(net "DPB_PWR_BTN_B")
		)
		(pad "P11" smd rect
			(at -10.795 -1.82499 180)
			(size 0.6096 2.3622)
			(layers "F.Cu" "F.Mask" "F.Paste")
			(net "UART_IOC_B_TX")
		)
		(pad "P12" smd rect
			(at -12.065 -1.82499 180)
			(size 0.6096 2.3622)
			(layers "F.Cu" "F.Mask" "F.Paste")
			(net "UART_IOC_B_RX")
		)
		(pad "P13" smd rect
			(at -13.335 -1.82499 180)
			(size 0.6096 2.3622)
			(layers "F.Cu" "F.Mask" "F.Paste")
			(net "GND")
		)
		(pad "P14" smd rect
			(at -14.605 -1.82499 180)
			(size 0.6096 2.3622)
			(layers "F.Cu" "F.Mask" "F.Paste")
			(net "UART_EXP_B_TX")
		)
		(pad "P15" smd rect
			(at -15.875 -1.82499 180)
			(size 0.6096 2.3622)
			(layers "F.Cu" "F.Mask" "F.Paste")
			(net "UART_EXP_B_RX")
		)
		(pad "S1" smd rect
			(at 15.875 -1.82499 180)
			(size 0.6096 2.3622)
			(layers "F.Cu" "F.Mask" "F.Paste")
			(net "UART_EXP_A_TX")
		)
		(pad "S2" smd rect
			(at 14.605 -1.82499 180)
			(size 0.6096 2.3622)
			(layers "F.Cu" "F.Mask" "F.Paste")
			(net "UART_EXP_A_RX")
		)
		(pad "S3" smd rect
			(at 13.335 -1.82499 180)
			(size 0.6096 2.3622)
			(layers "F.Cu" "F.Mask" "F.Paste")
			(net "GND")
		)
		(pad "S4" smd rect
			(at 12.065 -1.82499 180)
			(size 0.6096 2.3622)
			(layers "F.Cu" "F.Mask" "F.Paste")
			(net "UART_IOC_A_TX")
		)
		(pad "S5" smd rect
			(at 10.795 -1.82499 180)
			(size 0.6096 2.3622)
			(layers "F.Cu" "F.Mask" "F.Paste")
			(net "UART_IOC_A_RX")
		)
		(pad "S6" smd rect
			(at 9.525 -1.82499 180)
			(size 0.6096 2.3622)
			(layers "F.Cu" "F.Mask" "F.Paste")
			(net "GND")
		)
		(pad "S7" smd rect
			(at 8.255 -1.82499 180)
			(size 0.6096 2.3622)
			(layers "F.Cu" "F.Mask" "F.Paste")
			(net "DPB_PWR_BTN_A")
		)
		(pad "S8" smd rect
			(at 7.480046 2.845054 180)
			(size 0.508 2.3622)
			(layers "F.Cu" "F.Mask" "F.Paste")
			(net "I2C_DPB_A_SCL_BUF")
		)
		(pad "S9" smd rect
			(at 6.679946 2.845054 180)
			(size 0.508 2.3622)
			(layers "F.Cu" "F.Mask" "F.Paste")
			(net "I2C_DPB_A_SDA_BUF")
		)
		(pad "S10" smd rect
			(at 5.8801 2.845054 180)
			(size 0.508 2.3622)
			(layers "F.Cu" "F.Mask" "F.Paste")
			(net "RST_BTN_A_N")
		)
		(pad "S11" smd rect
			(at 5.08 2.845054 180)
			(size 0.508 2.3622)
			(layers "F.Cu" "F.Mask" "F.Paste")
			(net "P3V3_STBY_A")
		)
		(pad "S12" smd rect
			(at 4.2799 2.845054 180)
			(size 0.508 2.3622)
			(layers "F.Cu" "F.Mask" "F.Paste")
			(net "SYS_PWR_LED_A")
		)
		(pad "S13" smd rect
			(at 3.480054 2.845054 180)
			(size 0.508 2.3622)
			(layers "F.Cu" "F.Mask" "F.Paste")
			(net "ENCL_FAULT_LED_A")
		)
		(pad "S14" smd rect
			(at 2.679954 2.845054 180)
			(size 0.508 2.3622)
			(layers "F.Cu" "F.Mask" "F.Paste")
			(net "Net_1196")
		)
		(zone
			(layer "F.Cu")
			(hatch none 0.5)
			(connect_pads
				(clearance 0)
			)
			(min_thickness 0.25)
			(keepout
				(tracks not_allowed)
				(vias allowed)
				(pads allowed)
				(copperpour not_allowed)
				(footprints allowed)
			)
			(placement
				(enabled no)
				(sheetname "")
			)
			(fill
				(thermal_gap 0.5)
				(thermal_bridge_width 0.5)
				(island_removal_mode 0)
			)
			(polygon
				(pts
					(xy 243.411502 32.907478) (xy 243.411502 25.833578) (xy 236.477302 25.833578) (xy 236.477302 26.938478)
					(xy 240.592102 26.938478) (xy 240.592102 31.561278) (xy 236.477302 31.561278) (xy 236.477302 32.907478)
				)
			)
		)
		(zone
			(layer "F.Cu")
			(hatch none 0.5)
			(connect_pads
				(clearance 0)
			)
			(min_thickness 0.25)
			(keepout
				(tracks allowed)
				(vias not_allowed)
				(pads allowed)
				(copperpour not_allowed)
				(footprints allowed)
			)
			(placement
				(enabled no)
				(sheetname "")
			)
			(fill
				(thermal_gap 0.5)
				(thermal_bridge_width 0.5)
				(island_removal_mode 0)
			)
			(polygon
				(pts
					(xy 243.411502 32.907478) (xy 243.411502 25.833578) (xy 236.477302 25.833578) (xy 236.477302 26.938478)
					(xy 240.592102 26.938478) (xy 240.592102 31.561278) (xy 236.477302 31.561278) (xy 236.477302 32.907478)
				)
			)
		)
		(zone
			(layer "F.Cu")
			(hatch none 0.5)
			(connect_pads
				(clearance 0)
			)
			(min_thickness 0.25)
			(keepout
				(tracks allowed)
				(vias not_allowed)
				(pads allowed)
				(copperpour not_allowed)
				(footprints allowed)
			)
			(placement
				(enabled no)
				(sheetname "")
			)
			(fill
				(thermal_gap 0.5)
				(thermal_bridge_width 0.5)
				(island_removal_mode 0)
			)
			(polygon
				(pts
					(xy 276.888702 32.907478) (xy 276.888702 25.833578) (xy 283.822902 25.833578) (xy 283.822902 26.938478)
					(xy 279.708102 26.938478) (xy 279.708102 31.561278) (xy 283.822902 31.561278) (xy 283.822902 32.907478)
				)
			)
		)
		(zone
			(layer "F.Cu")
			(hatch none 0.5)
			(connect_pads
				(clearance 0)
			)
			(min_thickness 0.25)
			(keepout
				(tracks not_allowed)
				(vias allowed)
				(pads allowed)
				(copperpour not_allowed)
				(footprints allowed)
			)
			(placement
				(enabled no)
				(sheetname "")
			)
			(fill
				(thermal_gap 0.5)
				(thermal_bridge_width 0.5)
				(island_removal_mode 0)
			)
			(polygon
				(pts
					(xy 276.888702 32.907478) (xy 276.888702 25.833578) (xy 283.822902 25.833578) (xy 283.822902 26.938478)
					(xy 279.708102 26.938478) (xy 279.708102 31.561278) (xy 283.822902 31.561278) (xy 283.822902 32.907478)
				)
			)
		)
		(zone
			(layers "F.Cu" "B.Cu" "In1.Cu" "In2.Cu" "In3.Cu" "In4.Cu" "In5.Cu" "In6.Cu"
				"In7.Cu" "In8.Cu" "In9.Cu" "In10.Cu"
			)
			(hatch none 0.5)
			(connect_pads
				(clearance 0)
			)
			(min_thickness 0.25)
			(keepout
				(tracks not_allowed)
				(vias allowed)
				(pads allowed)
				(copperpour not_allowed)
				(footprints allowed)
			)
			(placement
				(enabled no)
				(sheetname "")
			)
			(fill
				(thermal_gap 0.5)
				(thermal_bridge_width 0.5)
				(island_removal_mode 0)
			)
			(polygon
				(pts
					(arc
						(start 242.049808 29.249878)
						(mid 240.500408 29.249878)
						(end 242.049808 29.249878)
					)
				)
			)
		)
		(zone
			(layers "F.Cu" "B.Cu" "In1.Cu" "In2.Cu" "In3.Cu" "In4.Cu" "In5.Cu" "In6.Cu"
				"In7.Cu" "In8.Cu" "In9.Cu" "In10.Cu"
			)
			(hatch none 0.5)
			(connect_pads
				(clearance 0)
			)
			(min_thickness 0.25)
			(keepout
				(tracks not_allowed)
				(vias allowed)
				(pads allowed)
				(copperpour not_allowed)
				(footprints allowed)
			)
			(placement
				(enabled no)
				(sheetname "")
			)
			(fill
				(thermal_gap 0.5)
				(thermal_bridge_width 0.5)
				(island_removal_mode 0)
			)
			(polygon
				(pts
					(arc
						(start 280.002996 29.249878)
						(mid 278.047196 29.249878)
						(end 280.002996 29.249878)
					)
				)
			)
		)
	)
)
